# T6G (Grand Teton) — schematic netlist excerpt (pin names and nets, part order shuffled) for the footprints in the layout excerpt that follows; sources: Cadence DE-HDL packaged netlist, KiCad conversion of 04192023_DAF0TMB3IC0_F0TG_MB_C_brd_V02_OCP.brd

J32  SCONN288_DDR506112002KQ  IO  pkg DDR288S_1-1VXC  page 102
  VIN_BULK0  = P12V_MEM_CPU1
  RFU0  = NC
  VIN_MGMT  = P3V3_AUX
  HSCL  = I3C_SPD_DDRE_CPU1_SCL
  HSDA  = I3C_SPD_DDRE_CPU1_SDA
  VSS0  = GND
  DQ0_A  = M_E_CPU1_SA_DQ<0>
  VSS1  = GND
  DQ1_A  = M_E_CPU1_SA_DQ<1>
  VSS2  = GND
  DQS0_A_T  = M_E_CPU1_SA_DQS_DP<0>
  DQS0_A_C  = M_E_CPU1_SA_DQS_DN<0>
  VSS3  = GND
  DQ4_A  = M_E_CPU1_SA_DQ<4>
  VSS4  = GND
  DQ5_A  = M_E_CPU1_SA_DQ<5>
  VSS5  = GND
  DQ8_A  = M_E_CPU1_SA_DQ<8>
  VSS6  = GND
  DQ9_A  = M_E_CPU1_SA_DQ<9>
  VSS7  = GND
  DQS1_A_T  = M_E_CPU1_SA_DQS_DP<1>
  DQS1_A_C  = M_E_CPU1_SA_DQS_DN<1>
  VSS8  = GND
  DQ12_A  = M_E_CPU1_SA_DQ<12>
  VSS9  = GND
  DQ13_A  = M_E_CPU1_SA_DQ<13>
  VSS10  = GND
  DQ16_A  = M_E_CPU1_SA_DQ<16>
  VSS11  = GND
  DQ17_A  = M_E_CPU1_SA_DQ<17>
  VSS12  = GND
  DQS2_A_T  = M_E_CPU1_SA_DQS_DP<2>
  DQS2_A_C  = M_E_CPU1_SA_DQS_DN<2>
  VSS13  = GND
  DQ20_A  = M_E_CPU1_SA_DQ<20>
  VSS14  = GND
  DQ21_A  = M_E_CPU1_SA_DQ<21>
  VSS15  = GND
  DQ24_A  = M_E_CPU1_SA_DQ<24>
  VSS16  = GND
  DQ25_A  = M_E_CPU1_SA_DQ<25>
  VSS17  = GND
  DQS3_A_T  = M_E_CPU1_SA_DQS_DP<3>
  DQS3_A_C  = M_E_CPU1_SA_DQS_DN<3>
  VSS18  = GND
  DQ28_A  = M_E_CPU1_SA_DQ<28>
  VSS19  = GND
  DQ29_A  = M_E_CPU1_SA_DQ<29>
  VSS20  = GND
  CB0_A  = M_E_CPU1_SA_CB<0>
  VSS21  = GND
  CB1_A  = M_E_CPU1_SA_CB<1>
  VSS22  = GND
  DQS4_A_T  = M_E_CPU1_SA_DQS_DP<4>
  DQS4_A_C  = M_E_CPU1_SA_DQS_DN<4>
  VSS23  = GND
  CB4_A  = M_E_CPU1_SA_CB<4>
  VSS24  = GND
  CB5_A  = M_E_CPU1_SA_CB<5>
  VSS25  = GND
  ALERT_N  = M_E_CPU1_ALERT_N
  VSS26  = GND
  CS0_A_N  = M_E_CPU1_SA_CS_N<0>
  VSS27  = GND
  CA0_A  = M_E_CPU1_SA_CA<0>
  VSS28  = GND
  CA2_A  = M_E_CPU1_SA_CA<2>
  VSS29  = GND
  CA4_A  = M_E_CPU1_SA_CA<4>
  VSS30  = GND
  CA6_A  = M_E_CPU1_SA_CA<6>
  VSS31  = GND
  PAR_A  = M_E_CPU1_SA_PAR
  VSS32  = GND
  CA0_B  = M_E_CPU1_SB_CA<0>
  VSS33  = GND
  CA2_B  = M_E_CPU1_SB_CA<2>
  VSS34  = GND
  CA4_B  = M_E_CPU1_SB_CA<4>
  VSS35  = GND
  CA6_B  = M_E_CPU1_SB_CA<6>
  VSS36  = GND
  CS0_B_N  = M_E_CPU1_SB_CS_N<0>
  VSS37  = GND
  \lbd||rsp_a_n\  = M_E_CPU1_SA_RSP<0>
  \lbs||rsp_b_n\  = M_E_CPU1_SB_RSP<0>
  VSS38  = GND
  CB4_B  = M_E_CPU1_SB_CB<4>
  VSS39  = GND
  CB5_B  = M_E_CPU1_SB_CB<5>
  VSS40  = GND
  \dqs9_b_t||tdqs9_b_t||dbi4_b_n\  = M_E_CPU1_SB_DQS_DP<9>
  \dqs9_b_c||tdqs9_b_c\  = M_E_CPU1_SB_DQS_DN<9>
  VSS41  = GND
  CB0_B  = M_E_CPU1_SB_CB<0>
  VSS42  = GND
  CB1_B  = M_E_CPU1_SB_CB<1>
  VSS43  = GND
  DQ0_B  = M_E_CPU1_SB_DQ<0>
  VSS44  = GND
  DQ1_B  = M_E_CPU1_SB_DQ<1>
  VSS45  = GND
  DQS0_B_T  = M_E_CPU1_SB_DQS_DP<0>
  DQS0_B_C  = M_E_CPU1_SB_DQS_DN<0>
  VSS46  = GND
  DQ4_B  = M_E_CPU1_SB_DQ<4>
  VSS47  = GND
  DQ5_B  = M_E_CPU1_SB_DQ<5>
  VSS48  = GND
  DQ8_B  = M_E_CPU1_SB_DQ<8>
  VSS49  = GND
  DQ9_B  = M_E_CPU1_SB_DQ<9>
  VSS50  = GND
  DQS1_B_T  = M_E_CPU1_SB_DQS_DP<1>
  DQS1_B_C  = M_E_CPU1_SB_DQS_DN<1>
  VSS51  = GND
  DQ12_B  = M_E_CPU1_SB_DQ<12>
  VSS52  = GND
  DQ13_B  = M_E_CPU1_SB_DQ<13>
  VSS53  = GND
  DQ16_B  = M_E_CPU1_SB_DQ<16>
  VSS54  = GND
  DQ17_B  = M_E_CPU1_SB_DQ<17>
  VSS55  = GND
  DQS2_B_T  = M_E_CPU1_SB_DQS_DP<2>
  DQS2_B_C  = M_E_CPU1_SB_DQS_DN<2>
  VSS56  = GND
  DQ20_B  = M_E_CPU1_SB_DQ<20>
  VSS57  = GND
  DQ21_B  = M_E_CPU1_SB_DQ<21>
  VSS58  = GND
  DQ24_B  = M_E_CPU1_SB_DQ<24>
  VSS59  = GND
  DQ25_B  = M_E_CPU1_SB_DQ<25>
  VSS60  = GND
  DQS3_B_T  = M_E_CPU1_SB_DQS_DP<3>
  DQS3_B_C  = M_E_CPU1_SB_DQS_DN<3>
  VSS61  = GND
  DQ28_B  = M_E_CPU1_SB_DQ<28>
  VSS62  = GND
  DQ29_B  = M_E_CPU1_SB_DQ<29>
  VSS63  = GND
  RFU1  = NC
  VIN_BULK1  = P12V_MEM_CPU1
  VIN_BULK2  = P12V_MEM_CPU1
  \pwr_good||fail_n\  = PWRGD_CHE_CPU1_DIMM
  HAS  = PD_CHE_CPU1_DIMM_SAA
  RFU2  = NC
  RFU3  = NC
  VSS64  = GND
  DQ2_A  = M_E_CPU1_SA_DQ<2>
  VSS65  = GND
  DQ3_A  = M_E_CPU1_SA_DQ<3>
  VSS66  = GND
  \dqs5_a_c||tdqs5_a_c||dqs5_a_t||tdqs5_a_t\  = M_E_CPU1_SA_DQS_DN<5>
  \dqs5_a_t||tdqs5_a_t\  = M_E_CPU1_SA_DQS_DP<5>
  VSS67  = GND
  DQ6_A  = M_E_CPU1_SA_DQ<6>
  VSS68  = GND
  DQ7_A  = M_E_CPU1_SA_DQ<7>
  VSS69  = GND
  DQ10_A  = M_E_CPU1_SA_DQ<10>
  VSS70  = GND
  DQ11_A  = M_E_CPU1_SA_DQ<11>
  VSS71  = GND
  \dqs6_a_c||tdqs6_a_c||dqs6_a_t||tdqs6_a_t\  = M_E_CPU1_SA_DQS_DN<6>
  \dqs6_a_t||tdqs6_a_t\  = M_E_CPU1_SA_DQS_DP<6>
  VSS72  = GND
  DQ14_A  = M_E_CPU1_SA_DQ<14>
  VSS73  = GND
  DQ15_A  = M_E_CPU1_SA_DQ<15>
  VSS74  = GND
  DQ18_A  = M_E_CPU1_SA_DQ<18>
  VSS75  = GND
  DQ19_A  = M_E_CPU1_SA_DQ<19>
  VSS76  = GND
  \dqs7_a_c||tdqs7_a_c\  = M_E_CPU1_SA_DQS_DN<7>
  \dqs7_a_t||tdqs7_a_t\  = M_E_CPU1_SA_DQS_DP<7>
  VSS77  = GND
  DQ22_A  = M_E_CPU1_SA_DQ<22>
  VSS78  = GND
  DQ23_A  = M_E_CPU1_SA_DQ<23>
  VSS79  = GND
  DQ26_A  = M_E_CPU1_SA_DQ<26>
  VSS80  = GND
  DQ27_A  = M_E_CPU1_SA_DQ<27>
  VSS81  = GND
  \dqs8_a_c||tdqs8_a_c\  = M_E_CPU1_SA_DQS_DN<8>
  \dqs8_a_t||tdqs8_a_t\  = M_E_CPU1_SA_DQS_DP<8>
  VSS82  = GND
  DQ30_A  = M_E_CPU1_SA_DQ<30>
  VSS83  = GND
  DQ31_A  = M_E_CPU1_SA_DQ<31>
  VSS84  = GND
  CB2_A  = M_E_CPU1_SA_CB<2>
  VSS85  = GND
  CB3_A  = M_E_CPU1_SA_CB<3>
  VSS86  = GND
  \dqs9_a_c||tdqs9_a_c\  = M_E_CPU1_SA_DQS_DN<9>
  \dqs9_a_t||tdqs9_a_t\  = M_E_CPU1_SA_DQS_DP<9>
  VSS87  = GND
  CB6_A  = M_E_CPU1_SA_CB<6>
  VSS88  = GND
  CB7_A  = M_E_CPU1_SA_CB<7>
  VSS89  = GND
  RESET_N  = M_E_CPU1_RESET_N
  VSS90  = GND
  CS1_A_N  = M_E_CPU1_SA_CS_N<1>
  VSS91  = GND
  CA1_A  = M_E_CPU1_SA_CA<1>
  VSS92  = GND
  CA3_A  = M_E_CPU1_SA_CA<3>
  VSS93  = GND
  CA5_A  = M_E_CPU1_SA_CA<5>
  VSS94  = GND
  CK_T  = M_E_CPU1_CLK_DP<0>
  CK_C  = M_E_CPU1_CLK_DN<0>
  VSS95  = GND
  RFU4  = NC
  CA1_B  = M_E_CPU1_SB_CA<1>
  VSS96  = GND
  CA3_B  = M_E_CPU1_SB_CA<3>
  VSS97  = GND
  CA5_B  = M_E_CPU1_SB_CA<5>
  VSS98  = GND
  PAR_B  = M_E_CPU1_SB_PAR
  VSS99  = GND
  CS1_B_N  = M_E_CPU1_SB_CS_N<1>
  VSS100  = GND
  RFU5  = NC
  RFU6  = NC
  VSS101  = GND
  CB6_B  = M_E_CPU1_SB_CB<6>
  VSS102  = GND
  CB7_B  = M_E_CPU1_SB_CB<7>
  VSS103  = GND
  DQS4_B_C  = M_E_CPU1_SB_DQS_DN<4>
  DQS4_B_T  = M_E_CPU1_SB_DQS_DP<4>
  VSS104  = GND
  CB2_B  = M_E_CPU1_SB_CB<2>
  VSS105  = GND
  CB3_B  = M_E_CPU1_SB_CB<3>
  VSS106  = GND
  DQ2_B  = M_E_CPU1_SB_DQ<2>
  VSS107  = GND
  DQ3_B  = M_E_CPU1_SB_DQ<3>
  VSS108  = GND
  \dqs5_b_c||tdqs5_b_c\  = M_E_CPU1_SB_DQS_DN<5>
  \dqs5_b_t||tdqs5_b_t\  = M_E_CPU1_SB_DQS_DP<5>
  VSS109  = GND
  DQ6_B  = M_E_CPU1_SB_DQ<6>
  VSS110  = GND
  DQ7_B  = M_E_CPU1_SB_DQ<7>
  VSS111  = GND
  DQ10_B  = M_E_CPU1_SB_DQ<10>
  VSS112  = GND
  DQ11_B  = M_E_CPU1_SB_DQ<11>
  VSS113  = GND
  \dqs6_b_c||tdqs6_b_c\  = M_E_CPU1_SB_DQS_DN<6>
  \dqs6_b_t||tdqs6_b_t\  = M_E_CPU1_SB_DQS_DP<6>
  VSS114  = GND
  DQ14_B  = M_E_CPU1_SB_DQ<14>
  VSS115  = GND
  DQ15_B  = M_E_CPU1_SB_DQ<15>
  VSS116  = GND
  DQ18_B  = M_E_CPU1_SB_DQ<18>
  VSS117  = GND
  DQ19_B  = M_E_CPU1_SB_DQ<19>
  VSS118  = GND
  \dqs7_b_c||tdqs7_b_c\  = M_E_CPU1_SB_DQS_DN<7>
  \dqs7_b_t||tdqs7_b_t\  = M_E_CPU1_SB_DQS_DP<7>
  VSS119  = GND
  DQ22_B  = M_E_CPU1_SB_DQ<22>
  VSS120  = GND
  DQ23_B  = M_E_CPU1_SB_DQ<23>
  VSS121  = GND
  DQ26_B  = M_E_CPU1_SB_DQ<26>
  VSS122  = GND
  DQ27_B  = M_E_CPU1_SB_DQ<27>
  VSS123  = GND
  \dqs8_b_c||tdqs8_b_c\  = M_E_CPU1_SB_DQS_DN<8>
  \dqs8_b_t||tdqs8_b_t\  = M_E_CPU1_SB_DQS_DP<8>
  VSS124  = GND
  DQ30_B  = M_E_CPU1_SB_DQ<30>
  VSS125  = GND
  DQ31_B  = M_E_CPU1_SB_DQ<31>
  VSS126  = GND
  G1  = GND
  G2  = GND
  G3  = GND

(kicad_pcb
	(version 20260206)
	(generator "pcbnew")
	(generator_version "10.0")
	(general
		(thickness 1.6)
		(legacy_teardrops no)
	)
	(paper "A4")
	(title_block
		(title "04192023_DAF0TMB3IC0_F0TG_MB_C_brd_V02_OCP.brd")
		(comment 1 "Grand Teton / footprint 4612 of 8354 (J32), pads 139-184 of 291")
	)
	(layers
		(0 "F.Cu" signal "TOP")
		(4 "In1.Cu" signal "GND")
		(6 "In2.Cu" signal "IN1")
		(8 "In3.Cu" signal "GND1")
		(10 "In4.Cu" signal "IN2")
		(12 "In5.Cu" signal "GND2")
		(14 "In6.Cu" signal "IN3")
		(16 "In7.Cu" signal "GND3")
		(18 "In8.Cu" signal "VCC")
		(20 "In9.Cu" signal "VCC1")
		(22 "In10.Cu" signal "GND4")
		(24 "In11.Cu" signal "IN4")
		(26 "In12.Cu" signal "GND5")
		(28 "In13.Cu" signal "IN5")
		(30 "In14.Cu" signal "GND6")
		(32 "In15.Cu" signal "IN6")
		(34 "In16.Cu" signal "GND7")
		(2 "B.Cu" signal "BOTTOM")
		(9 "F.Adhes" user "F.Adhesive")
		(11 "B.Adhes" user "B.Adhesive")
		(13 "F.Paste" user "Package Geometry/Pastemask Top")
		(15 "B.Paste" user "Package Geometry/Pastemask Bottom")
		(5 "F.SilkS" user "Ref Des/Silkscreen Top")
		(7 "B.SilkS" user "Ref Des/Silkscreen Bottom")
		(1 "F.Mask" user "Board Geometry/Soldermask Top")
		(3 "B.Mask" user "Board Geometry/Soldermask Bottom")
		(17 "Dwgs.User" user "User.Drawings")
		(19 "Cmts.User" user "User.Comments")
		(21 "Eco1.User" user "User.Eco1")
		(23 "Eco2.User" user "User.Eco2")
		(25 "Edge.Cuts" user "Board Geometry/Outline")
		(27 "Margin" user)
		(31 "F.CrtYd" user "Package Geometry/Place Bound Top")
		(29 "B.CrtYd" user "Package Geometry/Place Bound Bottom")
		(35 "F.Fab" user "Ref Des/Assembly Top")
		(33 "B.Fab" user "Ref Des/Assembly Bottom")
	)
	(footprint ""
		(layer "F.Cu")
		(at 27.20213 -255.560322 180)
		(property "Reference" "J32"
			(at 1.80086 -81.974436 0)
			(unlocked yes)
			(layer "F.SilkS")
			(effects
				(font
					(size 0.7874 0.5842)
					(thickness 0.1524)
				)
			)
		)
		(property "Value" ""
			(at 0 0 180)
			(layer "F.Fab")
			(effects
				(font
					(size 1.27 1.27)
				)
			)
		)
		(duplicate_pad_numbers_are_jumpers no)
		(pad "139" smd rect
			(at -2.050034 59.075066 90)
			(size 0.519938 1.4986)
			(layers "F.Cu" "F.Mask" "F.Paste")
			(net "GND")
		)
		(pad "140" smd rect
			(at -2.050034 59.92495 90)
			(size 0.519938 1.4986)
			(layers "F.Cu" "F.Mask" "F.Paste")
			(net "M_E_CPU1_SB_DQ<28>")
		)
		(pad "141" smd rect
			(at -2.050034 60.775088 90)
			(size 0.519938 1.4986)
			(layers "F.Cu" "F.Mask" "F.Paste")
			(net "GND")
		)
		(pad "142" smd rect
			(at -2.050034 61.624972 90)
			(size 0.519938 1.4986)
			(layers "F.Cu" "F.Mask" "F.Paste")
			(net "M_E_CPU1_SB_DQ<29>")
		)
		(pad "143" smd rect
			(at -2.050034 62.47511 90)
			(size 0.519938 1.4986)
			(layers "F.Cu" "F.Mask" "F.Paste")
			(net "GND")
		)
		(pad "144" smd rect
			(at -2.050034 63.324994 90)
			(size 0.519938 1.4986)
			(layers "F.Cu" "F.Mask" "F.Paste")
			(net "Net_2313")
		)
		(pad "145" smd rect
			(at 2.050034 -63.324994 90)
			(size 0.519938 1.4986)
			(layers "F.Cu" "F.Mask" "F.Paste")
			(net "P12V_MEM_CPU1")
		)
		(pad "146" smd rect
			(at 2.050034 -62.47511 90)
			(size 0.519938 1.4986)
			(layers "F.Cu" "F.Mask" "F.Paste")
			(net "P12V_MEM_CPU1")
		)
		(pad "147" smd rect
			(at 2.050034 -61.624972 90)
			(size 0.519938 1.4986)
			(layers "F.Cu" "F.Mask" "F.Paste")
			(net "PWRGD_CHE_CPU1_DIMM")
		)
		(pad "148" smd rect
			(at 2.050034 -60.775088 90)
			(size 0.519938 1.4986)
			(layers "F.Cu" "F.Mask" "F.Paste")
			(net "PD_CHE_CPU1_DIMM_SAA")
		)
		(pad "149" smd rect
			(at 2.050034 -59.92495 90)
			(size 0.519938 1.4986)
			(layers "F.Cu" "F.Mask" "F.Paste")
			(net "Net_2314")
		)
		(pad "150" smd rect
			(at 2.050034 -59.075066 90)
			(size 0.519938 1.4986)
			(layers "F.Cu" "F.Mask" "F.Paste")
			(net "Net_2315")
		)
		(pad "151" smd rect
			(at 2.050034 -58.224928 90)
			(size 0.519938 1.4986)
			(layers "F.Cu" "F.Mask" "F.Paste")
			(net "GND")
		)
		(pad "152" smd rect
			(at 2.050034 -57.375044 90)
			(size 0.519938 1.4986)
			(layers "F.Cu" "F.Mask" "F.Paste")
			(net "M_E_CPU1_SA_DQ<2>")
		)
		(pad "153" smd rect
			(at 2.050034 -56.524906 90)
			(size 0.519938 1.4986)
			(layers "F.Cu" "F.Mask" "F.Paste")
			(net "GND")
		)
		(pad "154" smd rect
			(at 2.050034 -55.675022 90)
			(size 0.519938 1.4986)
			(layers "F.Cu" "F.Mask" "F.Paste")
			(net "M_E_CPU1_SA_DQ<3>")
		)
		(pad "155" smd rect
			(at 2.050034 -54.824884 90)
			(size 0.519938 1.4986)
			(layers "F.Cu" "F.Mask" "F.Paste")
			(net "GND")
		)
		(pad "156" smd rect
			(at 2.050034 -53.975 90)
			(size 0.519938 1.4986)
			(layers "F.Cu" "F.Mask" "F.Paste")
			(net "M_E_CPU1_SA_DQS_DN<5>")
		)
		(pad "157" smd rect
			(at 2.050034 -53.125116 90)
			(size 0.519938 1.4986)
			(layers "F.Cu" "F.Mask" "F.Paste")
			(net "M_E_CPU1_SA_DQS_DP<5>")
		)
		(pad "158" smd rect
			(at 2.050034 -52.274978 90)
			(size 0.519938 1.4986)
			(layers "F.Cu" "F.Mask" "F.Paste")
			(net "GND")
		)
		(pad "159" smd rect
			(at 2.050034 -51.425094 90)
			(size 0.519938 1.4986)
			(layers "F.Cu" "F.Mask" "F.Paste")
			(net "M_E_CPU1_SA_DQ<6>")
		)
		(pad "160" smd rect
			(at 2.050034 -50.574956 90)
			(size 0.519938 1.4986)
			(layers "F.Cu" "F.Mask" "F.Paste")
			(net "GND")
		)
		(pad "161" smd rect
			(at 2.050034 -49.725072 90)
			(size 0.519938 1.4986)
			(layers "F.Cu" "F.Mask" "F.Paste")
			(net "M_E_CPU1_SA_DQ<7>")
		)
		(pad "162" smd rect
			(at 2.050034 -48.874934 90)
			(size 0.519938 1.4986)
			(layers "F.Cu" "F.Mask" "F.Paste")
			(net "GND")
		)
		(pad "163" smd rect
			(at 2.050034 -48.02505 90)
			(size 0.519938 1.4986)
			(layers "F.Cu" "F.Mask" "F.Paste")
			(net "M_E_CPU1_SA_DQ<10>")
		)
		(pad "164" smd rect
			(at 2.050034 -47.174912 90)
			(size 0.519938 1.4986)
			(layers "F.Cu" "F.Mask" "F.Paste")
			(net "GND")
		)
		(pad "165" smd rect
			(at 2.050034 -46.325028 90)
			(size 0.519938 1.4986)
			(layers "F.Cu" "F.Mask" "F.Paste")
			(net "M_E_CPU1_SA_DQ<11>")
		)
		(pad "166" smd rect
			(at 2.050034 -45.47489 90)
			(size 0.519938 1.4986)
			(layers "F.Cu" "F.Mask" "F.Paste")
			(net "GND")
		)
		(pad "167" smd rect
			(at 2.050034 -44.625006 90)
			(size 0.519938 1.4986)
			(layers "F.Cu" "F.Mask" "F.Paste")
			(net "M_E_CPU1_SA_DQS_DN<6>")
		)
		(pad "168" smd rect
			(at 2.050034 -43.775122 90)
			(size 0.519938 1.4986)
			(layers "F.Cu" "F.Mask" "F.Paste")
			(net "M_E_CPU1_SA_DQS_DP<6>")
		)
		(pad "169" smd rect
			(at 2.050034 -42.924984 90)
			(size 0.519938 1.4986)
			(layers "F.Cu" "F.Mask" "F.Paste")
			(net "GND")
		)
		(pad "170" smd rect
			(at 2.050034 -42.0751 90)
			(size 0.519938 1.4986)
			(layers "F.Cu" "F.Mask" "F.Paste")
			(net "M_E_CPU1_SA_DQ<14>")
		)
		(pad "171" smd rect
			(at 2.050034 -41.224962 90)
			(size 0.519938 1.4986)
			(layers "F.Cu" "F.Mask" "F.Paste")
			(net "GND")
		)
		(pad "172" smd rect
			(at 2.050034 -40.375078 90)
			(size 0.519938 1.4986)
			(layers "F.Cu" "F.Mask" "F.Paste")
			(net "M_E_CPU1_SA_DQ<15>")
		)
		(pad "173" smd rect
			(at 2.050034 -39.52494 90)
			(size 0.519938 1.4986)
			(layers "F.Cu" "F.Mask" "F.Paste")
			(net "GND")
		)
		(pad "174" smd rect
			(at 2.050034 -38.675056 90)
			(size 0.519938 1.4986)
			(layers "F.Cu" "F.Mask" "F.Paste")
			(net "M_E_CPU1_SA_DQ<18>")
		)
		(pad "175" smd rect
			(at 2.050034 -37.824918 90)
			(size 0.519938 1.4986)
			(layers "F.Cu" "F.Mask" "F.Paste")
			(net "GND")
		)
		(pad "176" smd rect
			(at 2.050034 -36.975034 90)
			(size 0.519938 1.4986)
			(layers "F.Cu" "F.Mask" "F.Paste")
			(net "M_E_CPU1_SA_DQ<19>")
		)
		(pad "177" smd rect
			(at 2.050034 -36.124896 90)
			(size 0.519938 1.4986)
			(layers "F.Cu" "F.Mask" "F.Paste")
			(net "GND")
		)
		(pad "178" smd rect
			(at 2.050034 -35.275012 90)
			(size 0.519938 1.4986)
			(layers "F.Cu" "F.Mask" "F.Paste")
			(net "M_E_CPU1_SA_DQS_DN<7>")
		)
		(pad "179" smd rect
			(at 2.050034 -34.425128 90)
			(size 0.519938 1.4986)
			(layers "F.Cu" "F.Mask" "F.Paste")
			(net "M_E_CPU1_SA_DQS_DP<7>")
		)
		(pad "180" smd rect
			(at 2.050034 -33.57499 90)
			(size 0.519938 1.4986)
			(layers "F.Cu" "F.Mask" "F.Paste")
			(net "GND")
		)
		(pad "181" smd rect
			(at 2.050034 -32.725106 90)
			(size 0.519938 1.4986)
			(layers "F.Cu" "F.Mask" "F.Paste")
			(net "M_E_CPU1_SA_DQ<22>")
		)
		(pad "182" smd rect
			(at 2.050034 -31.874968 90)
			(size 0.519938 1.4986)
			(layers "F.Cu" "F.Mask" "F.Paste")
			(net "GND")
		)
		(pad "183" smd rect
			(at 2.050034 -31.025084 90)
			(size 0.519938 1.4986)
			(layers "F.Cu" "F.Mask" "F.Paste")
			(net "M_E_CPU1_SA_DQ<23>")
		)
		(pad "184" smd rect
			(at 2.050034 -30.174946 90)
			(size 0.519938 1.4986)
			(layers "F.Cu" "F.Mask" "F.Paste")
			(net "GND")
		)
	)
)
